(kicad_pcb
	(version 20260206)
	(generator "pcbnew")
	(generator_version "10.0")
	(general
		(thickness 1.6)
		(legacy_teardrops no)
	)
	(paper "A4")
	(title_block
		(title "9054_F0T_PDB_BD_GPU_F_V04_1213_1550_OCP.brd")
		(comment 1 "Grand Teton / footprints 66-72 of 608")
	)
	(layers
		(0 "F.Cu" signal "TOP")
		(4 "In1.Cu" signal "GND")
		(6 "In2.Cu" signal "IN1")
		(8 "In3.Cu" signal "GND1")
		(10 "In4.Cu" signal "VCC")
		(12 "In5.Cu" signal "VCC1")
		(14 "In6.Cu" signal "GND2")
		(16 "In7.Cu" signal "IN2")
		(18 "In8.Cu" signal "GND3")
		(2 "B.Cu" signal "BOTTOM")
		(9 "F.Adhes" user "F.Adhesive")
		(11 "B.Adhes" user "B.Adhesive")
		(13 "F.Paste" user "Package Geometry/Pastemask Top")
		(15 "B.Paste" user "Package Geometry/Pastemask Bottom")
		(5 "F.SilkS" user "Ref Des/Silkscreen Top")
		(7 "B.SilkS" user "Ref Des/Silkscreen Bottom")
		(1 "F.Mask" user "Board Geometry/Soldermask Top")
		(3 "B.Mask" user "Board Geometry/Soldermask Bottom")
		(17 "Dwgs.User" user "User.Drawings")
		(19 "Cmts.User" user "User.Comments")
		(21 "Eco1.User" user "User.Eco1")
		(23 "Eco2.User" user "User.Eco2")
		(25 "Edge.Cuts" user "Board Geometry/Outline")
		(27 "Margin" user)
		(31 "F.CrtYd" user "Package Geometry/Place Bound Top")
		(29 "B.CrtYd" user "Package Geometry/Place Bound Bottom")
		(35 "F.Fab" user "Ref Des/Assembly Top")
		(33 "B.Fab" user "Ref Des/Assembly Bottom")
	)
	(footprint ""
		(layer "F.Cu")
		(at 418.91458 -32.75076 90)
		(property "Reference" "C97"
			(at 0 0 90)
			(layer "F.SilkS")
			(hide yes)
			(effects
				(font
					(size 1.27 1.27)
				)
			)
		)
		(property "Value" ""
			(at 0 0 90)
			(layer "F.Fab")
			(effects
				(font
					(size 1.27 1.27)
				)
			)
		)
		(duplicate_pad_numbers_are_jumpers no)
		(fp_line
			(start 0.7874 -0.4064)
			(end 0.7874 0.4064)
			(stroke
				(width 0.1524)
				(type default)
			)
			(layer "F.SilkS")
		)
		(fp_line
			(start -0.7874 -0.4064)
			(end 0.7874 -0.4064)
			(stroke
				(width 0.1524)
				(type default)
			)
			(layer "F.SilkS")
		)
		(fp_line
			(start 0.7874 0.4064)
			(end -0.7874 0.4064)
			(stroke
				(width 0.1524)
				(type default)
			)
			(layer "F.SilkS")
		)
		(fp_line
			(start -0.7874 0.4064)
			(end -0.7874 -0.4064)
			(stroke
				(width 0.1524)
				(type default)
			)
			(layer "F.SilkS")
		)
		(fp_line
			(start -0.12065 -0.305054)
			(end -0.12065 -0.2794)
			(stroke
				(width 0.1)
				(type default)
			)
			(layer "F.Fab")
		)
		(fp_line
			(start -0.67945 -0.305054)
			(end -0.12065 -0.305054)
			(stroke
				(width 0.1)
				(type default)
			)
			(layer "F.Fab")
		)
		(fp_line
			(start 0.67945 -0.3048)
			(end 0.67945 0.3048)
			(stroke
				(width 0.1)
				(type default)
			)
			(layer "F.Fab")
		)
		(fp_line
			(start 0.12065 -0.3048)
			(end 0.67945 -0.3048)
			(stroke
				(width 0.1)
				(type default)
			)
			(layer "F.Fab")
		)
		(fp_line
			(start 0.12065 -0.2794)
			(end 0.12065 -0.3048)
			(stroke
				(width 0.1)
				(type default)
			)
			(layer "F.Fab")
		)
		(fp_line
			(start -0.12065 -0.2794)
			(end 0.12065 -0.2794)
			(stroke
				(width 0.1)
				(type default)
			)
			(layer "F.Fab")
		)
		(fp_line
			(start 0.120396 0.2794)
			(end -0.12065 0.2794)
			(stroke
				(width 0.1)
				(type default)
			)
			(layer "F.Fab")
		)
		(fp_line
			(start -0.12065 0.2794)
			(end -0.12065 0.3048)
			(stroke
				(width 0.1)
				(type default)
			)
			(layer "F.Fab")
		)
		(fp_line
			(start 0.67945 0.3048)
			(end 0.120396 0.3048)
			(stroke
				(width 0.1)
				(type default)
			)
			(layer "F.Fab")
		)
		(fp_line
			(start 0.120396 0.3048)
			(end 0.120396 0.2794)
			(stroke
				(width 0.1)
				(type default)
			)
			(layer "F.Fab")
		)
		(fp_line
			(start -0.12065 0.3048)
			(end -0.67945 0.3048)
			(stroke
				(width 0.1)
				(type default)
			)
			(layer "F.Fab")
		)
		(fp_line
			(start -0.67945 0.3048)
			(end -0.67945 -0.305054)
			(stroke
				(width 0.1)
				(type default)
			)
			(layer "F.Fab")
		)
		(pad "1" smd circle
			(at -0.40005 0 90)
			(size 0 0)
			(layers "F.Cu" "F.Mask" "F.Paste")
			(net "P12V_LED_TIMER")
		)
		(pad "2" smd circle
			(at 0.40005 0 90)
			(size 0 0)
			(layers "F.Cu" "F.Mask" "F.Paste")
			(net "GND")
		)
	)
	(footprint ""
		(layer "F.Cu")
		(at 33.85439 -41.529 180)
		(property "Reference" "R39"
			(at 0 0 180)
			(layer "F.SilkS")
			(hide yes)
			(effects
				(font
					(size 1.27 1.27)
				)
			)
		)
		(property "Value" ""
			(at 0 0 180)
			(layer "F.Fab")
			(effects
				(font
					(size 1.27 1.27)
				)
			)
		)
		(duplicate_pad_numbers_are_jumpers no)
		(fp_line
			(start 2.234946 0.9271)
			(end -2.234946 0.9271)
			(stroke
				(width 0.1524)
				(type default)
			)
			(layer "F.SilkS")
		)
		(fp_line
			(start 2.234946 -0.9271)
			(end 2.234946 0.9271)
			(stroke
				(width 0.1524)
				(type default)
			)
			(layer "F.SilkS")
		)
		(fp_line
			(start -2.234946 0.9271)
			(end -2.234946 -0.9271)
			(stroke
				(width 0.1524)
				(type default)
			)
			(layer "F.SilkS")
		)
		(fp_line
			(start -2.234946 -0.9271)
			(end 2.234946 -0.9271)
			(stroke
				(width 0.1524)
				(type default)
			)
			(layer "F.SilkS")
		)
		(fp_line
			(start 1.575054 0.824992)
			(end 1.575054 -0.824992)
			(stroke
				(width 0.1)
				(type default)
			)
			(layer "F.Fab")
		)
		(fp_line
			(start 1.575054 -0.824992)
			(end -1.575054 -0.824992)
			(stroke
				(width 0.1)
				(type default)
			)
			(layer "F.Fab")
		)
		(fp_line
			(start -1.575054 0.824992)
			(end 1.575054 0.824992)
			(stroke
				(width 0.1)
				(type default)
			)
			(layer "F.Fab")
		)
		(fp_line
			(start -1.575054 -0.824992)
			(end -1.575054 0.824992)
			(stroke
				(width 0.1)
				(type default)
			)
			(layer "F.Fab")
		)
		(pad "1" smd rect
			(at -1.599946 0 180)
			(size 1.016 1.6002)
			(layers "F.Cu" "F.Mask" "F.Paste")
			(net "P52V_HS2")
		)
		(pad "2" smd rect
			(at 1.599946 0 180)
			(size 1.016 1.6002)
			(layers "F.Cu" "F.Mask" "F.Paste")
			(net "LED_D2_R1")
		)
	)
	(footprint ""
		(layer "F.Cu")
		(at 420.116 -50.546)
		(property "Reference" "R419"
			(at 0 0 0)
			(layer "F.SilkS")
			(hide yes)
			(effects
				(font
					(size 1.27 1.27)
				)
			)
		)
		(property "Value" ""
			(at 0 0 0)
			(layer "F.Fab")
			(effects
				(font
					(size 1.27 1.27)
				)
			)
		)
		(duplicate_pad_numbers_are_jumpers no)
		(fp_line
			(start -0.7874 -0.4064)
			(end 0.7874 -0.4064)
			(stroke
				(width 0.1524)
				(type default)
			)
			(layer "F.SilkS")
		)
		(fp_line
			(start -0.7874 0.4064)
			(end -0.7874 -0.4064)
			(stroke
				(width 0.1524)
				(type default)
			)
			(layer "F.SilkS")
		)
		(fp_line
			(start 0.7874 -0.4064)
			(end 0.7874 0.4064)
			(stroke
				(width 0.1524)
				(type default)
			)
			(layer "F.SilkS")
		)
		(fp_line
			(start 0.7874 0.4064)
			(end -0.7874 0.4064)
			(stroke
				(width 0.1524)
				(type default)
			)
			(layer "F.SilkS")
		)
		(fp_line
			(start -0.67945 -0.305054)
			(end -0.12065 -0.305054)
			(stroke
				(width 0.1)
				(type default)
			)
			(layer "F.Fab")
		)
		(fp_line
			(start -0.67945 0.3048)
			(end -0.67945 -0.305054)
			(stroke
				(width 0.1)
				(type default)
			)
			(layer "F.Fab")
		)
		(fp_line
			(start -0.12065 -0.305054)
			(end -0.12065 -0.2794)
			(stroke
				(width 0.1)
				(type default)
			)
			(layer "F.Fab")
		)
		(fp_line
			(start -0.12065 -0.2794)
			(end 0.12065 -0.2794)
			(stroke
				(width 0.1)
				(type default)
			)
			(layer "F.Fab")
		)
		(fp_line
			(start -0.12065 0.2794)
			(end -0.12065 0.3048)
			(stroke
				(width 0.1)
				(type default)
			)
			(layer "F.Fab")
		)
		(fp_line
			(start -0.12065 0.3048)
			(end -0.67945 0.3048)
			(stroke
				(width 0.1)
				(type default)
			)
			(layer "F.Fab")
		)
		(fp_line
			(start 0.120396 0.2794)
			(end -0.12065 0.2794)
			(stroke
				(width 0.1)
				(type default)
			)
			(layer "F.Fab")
		)
		(fp_line
			(start 0.120396 0.3048)
			(end 0.120396 0.2794)
			(stroke
				(width 0.1)
				(type default)
			)
			(layer "F.Fab")
		)
		(fp_line
			(start 0.12065 -0.3048)
			(end 0.67945 -0.3048)
			(stroke
				(width 0.1)
				(type default)
			)
			(layer "F.Fab")
		)
		(fp_line
			(start 0.12065 -0.2794)
			(end 0.12065 -0.3048)
			(stroke
				(width 0.1)
				(type default)
			)
			(layer "F.Fab")
		)
		(fp_line
			(start 0.67945 -0.3048)
			(end 0.67945 0.3048)
			(stroke
				(width 0.1)
				(type default)
			)
			(layer "F.Fab")
		)
		(fp_line
			(start 0.67945 0.3048)
			(end 0.120396 0.3048)
			(stroke
				(width 0.1)
				(type default)
			)
			(layer "F.Fab")
		)
		(pad "1" smd circle
			(at -0.40005 0)
			(size 0 0)
			(layers "F.Cu" "F.Mask" "F.Paste")
			(net "PWRGD_P52V_HS1_4287_PG")
		)
		(pad "2" smd circle
			(at 0.40005 0)
			(size 0 0)
			(layers "F.Cu" "F.Mask" "F.Paste")
			(net "PWRGD_P52V_HS1_PG")
		)
	)
	(footprint ""
		(layer "F.Cu")
		(at 208.810098 -79.624936)
		(property "Reference" "H32"
			(at -1.9812 -4.079748 0)
			(unlocked yes)
			(layer "B.SilkS")
			(effects
				(font
					(size 0.7874 0.5842)
					(thickness 0.1524)
				)
				(justify left mirror)
			)
		)
		(property "Value" ""
			(at 0 0 0)
			(layer "F.Fab")
			(effects
				(font
					(size 1.27 1.27)
				)
			)
		)
		(duplicate_pad_numbers_are_jumpers no)
		(pad "1" thru_hole circle
			(at 0 0)
			(size 8.001 8.001)
			(drill 4.2418)
			(layers "*.Cu" "*.Mask")
			(remove_unused_layers no)
			(net "TP_H32")
			(clearance -1.6256)
			(padstack
				(mode front_inner_back)
				(layer "Inner"
					(shape circle)
					(size 6.0198 6.0198)
					(clearance -0.635)
				)
				(layer "B.Cu"
					(shape circle)
					(size 8.001 8.001)
					(clearance -1.6256)
				)
			)
		)
		(zone
			(layers "F.Cu" "B.Cu" "In1.Cu" "In2.Cu" "In3.Cu" "In4.Cu" "In5.Cu" "In6.Cu"
				"In7.Cu" "In8.Cu"
			)
			(hatch none 0.5)
			(connect_pads
				(clearance 0)
			)
			(min_thickness 0.25)
			(keepout
				(tracks not_allowed)
				(vias allowed)
				(pads allowed)
				(copperpour not_allowed)
				(footprints allowed)
			)
			(placement
				(enabled no)
				(sheetname "")
			)
			(fill
				(thermal_gap 0.5)
				(thermal_bridge_width 0.5)
				(island_removal_mode 0)
			)
			(polygon
				(pts
					(arc
						(start 212.320124 -79.624936)
						(mid 205.300072 -79.624936)
						(end 212.320124 -79.624936)
					)
				)
			)
		)
	)
	(footprint ""
		(layer "F.Cu")
		(at 77.851 -45.4406)
		(property "Reference" "ME4"
			(at 0 0 0)
			(layer "F.SilkS")
			(hide yes)
			(effects
				(font
					(size 1.27 1.27)
				)
			)
		)
		(property "Value" ""
			(at 0 0 0)
			(layer "F.Fab")
			(effects
				(font
					(size 1.27 1.27)
				)
			)
		)
		(duplicate_pad_numbers_are_jumpers no)
		(fp_line
			(start 0 -6.999986)
			(end 0 -5.475986)
			(stroke
				(width 0.1524)
				(type default)
			)
			(layer "F.SilkS")
		)
		(fp_line
			(start 0 -1.524)
			(end 0 0)
			(stroke
				(width 0.1524)
				(type default)
			)
			(layer "F.SilkS")
		)
		(fp_line
			(start 0 0)
			(end 1.524 0)
			(stroke
				(width 0.1524)
				(type default)
			)
			(layer "F.SilkS")
		)
		(fp_line
			(start 1.524 -6.999986)
			(end 0 -6.999986)
			(stroke
				(width 0.1524)
				(type default)
			)
			(layer "F.SilkS")
		)
		(fp_line
			(start 5.475986 -6.999986)
			(end 6.999986 -6.999986)
			(stroke
				(width 0.1524)
				(type default)
			)
			(layer "F.SilkS")
		)
		(fp_line
			(start 6.999986 -6.999986)
			(end 6.999986 -5.475986)
			(stroke
				(width 0.1524)
				(type default)
			)
			(layer "F.SilkS")
		)
		(fp_line
			(start 6.999986 -1.524)
			(end 6.999986 0)
			(stroke
				(width 0.1524)
				(type default)
			)
			(layer "F.SilkS")
		)
		(fp_line
			(start 6.999986 0)
			(end 5.475986 0)
			(stroke
				(width 0.1524)
				(type default)
			)
			(layer "F.SilkS")
		)
		(fp_text user "S/N"
			(at 0.361188 -5.450078 0)
			(unlocked yes)
			(layer "F.SilkS")
			(effects
				(font
					(size 1.905 1.4224)
					(thickness 0.1524)
				)
				(justify left)
			)
		)
	)
	(footprint ""
		(layer "F.Cu")
		(at 436.245 -32.893)
		(property "Reference" "R22"
			(at 0 0 0)
			(layer "F.SilkS")
			(hide yes)
			(effects
				(font
					(size 1.27 1.27)
				)
			)
		)
		(property "Value" ""
			(at 0 0 0)
			(layer "F.Fab")
			(effects
				(font
					(size 1.27 1.27)
				)
			)
		)
		(duplicate_pad_numbers_are_jumpers no)
		(fp_line
			(start -0.7874 -0.4064)
			(end 0.7874 -0.4064)
			(stroke
				(width 0.1524)
				(type default)
			)
			(layer "F.SilkS")
		)
		(fp_line
			(start -0.7874 0.4064)
			(end -0.7874 -0.4064)
			(stroke
				(width 0.1524)
				(type default)
			)
			(layer "F.SilkS")
		)
		(fp_line
			(start 0.7874 -0.4064)
			(end 0.7874 0.4064)
			(stroke
				(width 0.1524)
				(type default)
			)
			(layer "F.SilkS")
		)
		(fp_line
			(start 0.7874 0.4064)
			(end -0.7874 0.4064)
			(stroke
				(width 0.1524)
				(type default)
			)
			(layer "F.SilkS")
		)
		(fp_line
			(start -0.67945 -0.305054)
			(end -0.12065 -0.305054)
			(stroke
				(width 0.1)
				(type default)
			)
			(layer "F.Fab")
		)
		(fp_line
			(start -0.67945 0.3048)
			(end -0.67945 -0.305054)
			(stroke
				(width 0.1)
				(type default)
			)
			(layer "F.Fab")
		)
		(fp_line
			(start -0.12065 -0.305054)
			(end -0.12065 -0.2794)
			(stroke
				(width 0.1)
				(type default)
			)
			(layer "F.Fab")
		)
		(fp_line
			(start -0.12065 -0.2794)
			(end 0.12065 -0.2794)
			(stroke
				(width 0.1)
				(type default)
			)
			(layer "F.Fab")
		)
		(fp_line
			(start -0.12065 0.2794)
			(end -0.12065 0.3048)
			(stroke
				(width 0.1)
				(type default)
			)
			(layer "F.Fab")
		)
		(fp_line
			(start -0.12065 0.3048)
			(end -0.67945 0.3048)
			(stroke
				(width 0.1)
				(type default)
			)
			(layer "F.Fab")
		)
		(fp_line
			(start 0.120396 0.2794)
			(end -0.12065 0.2794)
			(stroke
				(width 0.1)
				(type default)
			)
			(layer "F.Fab")
		)
		(fp_line
			(start 0.120396 0.3048)
			(end 0.120396 0.2794)
			(stroke
				(width 0.1)
				(type default)
			)
			(layer "F.Fab")
		)
		(fp_line
			(start 0.12065 -0.3048)
			(end 0.67945 -0.3048)
			(stroke
				(width 0.1)
				(type default)
			)
			(layer "F.Fab")
		)
		(fp_line
			(start 0.12065 -0.2794)
			(end 0.12065 -0.3048)
			(stroke
				(width 0.1)
				(type default)
			)
			(layer "F.Fab")
		)
		(fp_line
			(start 0.67945 -0.3048)
			(end 0.67945 0.3048)
			(stroke
				(width 0.1)
				(type default)
			)
			(layer "F.Fab")
		)
		(fp_line
			(start 0.67945 0.3048)
			(end 0.120396 0.3048)
			(stroke
				(width 0.1)
				(type default)
			)
			(layer "F.Fab")
		)
		(pad "1" smd circle
			(at -0.40005 0)
			(size 0 0)
			(layers "F.Cu" "F.Mask" "F.Paste")
			(net "P3V3_AUX")
		)
		(pad "2" smd circle
			(at 0.40005 0)
			(size 0 0)
			(layers "F.Cu" "F.Mask" "F.Paste")
			(net "PD_9543_FAN_A1")
		)
	)
	(footprint ""
		(layer "F.Cu")
		(at 380.803912 -17.907254 90)
		(property "Reference" "R74"
			(at 0 0 90)
			(layer "F.SilkS")
			(hide yes)
			(effects
				(font
					(size 1.27 1.27)
				)
			)
		)
		(property "Value" ""
			(at 0 0 90)
			(layer "F.Fab")
			(effects
				(font
					(size 1.27 1.27)
				)
			)
		)
		(duplicate_pad_numbers_are_jumpers no)
		(fp_line
			(start 0.7874 -0.4064)
			(end 0.7874 0.4064)
			(stroke
				(width 0.1524)
				(type default)
			)
			(layer "F.SilkS")
		)
		(fp_line
			(start -0.7874 -0.4064)
			(end 0.7874 -0.4064)
			(stroke
				(width 0.1524)
				(type default)
			)
			(layer "F.SilkS")
		)
		(fp_line
			(start 0.7874 0.4064)
			(end -0.7874 0.4064)
			(stroke
				(width 0.1524)
				(type default)
			)
			(layer "F.SilkS")
		)
		(fp_line
			(start -0.7874 0.4064)
			(end -0.7874 -0.4064)
			(stroke
				(width 0.1524)
				(type default)
			)
			(layer "F.SilkS")
		)
		(fp_line
			(start -0.12065 -0.305054)
			(end -0.12065 -0.2794)
			(stroke
				(width 0.1)
				(type default)
			)
			(layer "F.Fab")
		)
		(fp_line
			(start -0.67945 -0.305054)
			(end -0.12065 -0.305054)
			(stroke
				(width 0.1)
				(type default)
			)
			(layer "F.Fab")
		)
		(fp_line
			(start 0.67945 -0.3048)
			(end 0.67945 0.3048)
			(stroke
				(width 0.1)
				(type default)
			)
			(layer "F.Fab")
		)
		(fp_line
			(start 0.12065 -0.3048)
			(end 0.67945 -0.3048)
			(stroke
				(width 0.1)
				(type default)
			)
			(layer "F.Fab")
		)
		(fp_line
			(start 0.12065 -0.2794)
			(end 0.12065 -0.3048)
			(stroke
				(width 0.1)
				(type default)
			)
			(layer "F.Fab")
		)
		(fp_line
			(start -0.12065 -0.2794)
			(end 0.12065 -0.2794)
			(stroke
				(width 0.1)
				(type default)
			)
			(layer "F.Fab")
		)
		(fp_line
			(start 0.120396 0.2794)
			(end -0.12065 0.2794)
			(stroke
				(width 0.1)
				(type default)
			)
			(layer "F.Fab")
		)
		(fp_line
			(start -0.12065 0.2794)
			(end -0.12065 0.3048)
			(stroke
				(width 0.1)
				(type default)
			)
			(layer "F.Fab")
		)
		(fp_line
			(start 0.67945 0.3048)
			(end 0.120396 0.3048)
			(stroke
				(width 0.1)
				(type default)
			)
			(layer "F.Fab")
		)
		(fp_line
			(start 0.120396 0.3048)
			(end 0.120396 0.2794)
			(stroke
				(width 0.1)
				(type default)
			)
			(layer "F.Fab")
		)
		(fp_line
			(start -0.12065 0.3048)
			(end -0.67945 0.3048)
			(stroke
				(width 0.1)
				(type default)
			)
			(layer "F.Fab")
		)
		(fp_line
			(start -0.67945 0.3048)
			(end -0.67945 -0.305054)
			(stroke
				(width 0.1)
				(type default)
			)
			(layer "F.Fab")
		)
		(pad "1" smd circle
			(at -0.40005 0 90)
			(size 0 0)
			(layers "F.Cu" "F.Mask" "F.Paste")
			(net "RST_SMB_FAN_0_R_N")
		)
		(pad "2" smd circle
			(at 0.40005 0 90)
			(size 0 0)
			(layers "F.Cu" "F.Mask" "F.Paste")
			(net "RST_SMB_PDB_BUF_N")
		)
	)
)
